(kicad_pcb
	(version 20260206)
	(generator "pcbnew")
	(generator_version "10.0")
	(general
		(thickness 1.6)
		(legacy_teardrops no)
	)
	(paper "A4")
	(title_block
		(title "03242023_DA0F0TMBIJ0_F0T_Motherboard_J_brd_V01_OCP.brd")
		(comment 1 "Grand Teton / footprints 4118-4123 of 6105")
	)
	(layers
		(0 "F.Cu" signal "TOP")
		(4 "In1.Cu" signal "GND")
		(6 "In2.Cu" signal "IN1")
		(8 "In3.Cu" signal "GND1")
		(10 "In4.Cu" signal "IN2")
		(12 "In5.Cu" signal "GND2")
		(14 "In6.Cu" signal "IN3")
		(16 "In7.Cu" signal "GND3")
		(18 "In8.Cu" signal "VCC")
		(20 "In9.Cu" signal "VCC1")
		(22 "In10.Cu" signal "GND4")
		(24 "In11.Cu" signal "IN4")
		(26 "In12.Cu" signal "GND5")
		(28 "In13.Cu" signal "IN5")
		(30 "In14.Cu" signal "GND6")
		(32 "In15.Cu" signal "IN6")
		(34 "In16.Cu" signal "GND7")
		(2 "B.Cu" signal "BOTTOM")
		(9 "F.Adhes" user "F.Adhesive")
		(11 "B.Adhes" user "B.Adhesive")
		(13 "F.Paste" user "Package Geometry/Pastemask Top")
		(15 "B.Paste" user "Package Geometry/Pastemask Bottom")
		(5 "F.SilkS" user "Ref Des/Silkscreen Top")
		(7 "B.SilkS" user "Ref Des/Silkscreen Bottom")
		(1 "F.Mask" user "Board Geometry/Soldermask Top")
		(3 "B.Mask" user "Board Geometry/Soldermask Bottom")
		(17 "Dwgs.User" user "User.Drawings")
		(19 "Cmts.User" user "User.Comments")
		(21 "Eco1.User" user "User.Eco1")
		(23 "Eco2.User" user "User.Eco2")
		(25 "Edge.Cuts" user "Board Geometry/Outline")
		(27 "Margin" user)
		(31 "F.CrtYd" user "Package Geometry/Place Bound Top")
		(29 "B.CrtYd" user "Package Geometry/Place Bound Bottom")
		(35 "F.Fab" user "Ref Des/Assembly Top")
		(33 "B.Fab" user "Ref Des/Assembly Bottom")
	)
	(footprint ""
		(layer "F.Cu")
		(at 166.859204 -56.819038 90)
		(property "Reference" "C1921"
			(at 0 0 90)
			(layer "F.SilkS")
			(hide yes)
			(effects
				(font
					(size 1.27 1.27)
				)
			)
		)
		(property "Value" ""
			(at 0 0 90)
			(layer "F.Fab")
			(effects
				(font
					(size 1.27 1.27)
				)
			)
		)
		(duplicate_pad_numbers_are_jumpers no)
		(fp_line
			(start 1.2954 -0.5842)
			(end 1.2954 0.5842)
			(stroke
				(width 0.1524)
				(type default)
			)
			(layer "F.SilkS")
		)
		(fp_line
			(start 0 -0.5842)
			(end 0 0.5842)
			(stroke
				(width 0.1524)
				(type default)
			)
			(layer "F.SilkS")
		)
		(fp_line
			(start -1.2954 -0.5842)
			(end 1.2954 -0.5842)
			(stroke
				(width 0.1524)
				(type default)
			)
			(layer "F.SilkS")
		)
		(fp_line
			(start 1.2954 0.5842)
			(end -1.2954 0.5842)
			(stroke
				(width 0.1524)
				(type default)
			)
			(layer "F.SilkS")
		)
		(fp_line
			(start -1.2954 0.5842)
			(end -1.2954 -0.5842)
			(stroke
				(width 0.1524)
				(type default)
			)
			(layer "F.SilkS")
		)
		(fp_line
			(start 0.8636 -0.4572)
			(end 0.8636 -0.4064)
			(stroke
				(width 0.1)
				(type default)
			)
			(layer "F.Fab")
		)
		(fp_line
			(start -0.8636 -0.4572)
			(end 0.8636 -0.4572)
			(stroke
				(width 0.1)
				(type default)
			)
			(layer "F.Fab")
		)
		(fp_line
			(start 1.1938 -0.4064)
			(end 1.1938 0.4064)
			(stroke
				(width 0.1)
				(type default)
			)
			(layer "F.Fab")
		)
		(fp_line
			(start 0.8636 -0.4064)
			(end 1.1938 -0.4064)
			(stroke
				(width 0.1)
				(type default)
			)
			(layer "F.Fab")
		)
		(fp_line
			(start -0.8636 -0.4064)
			(end -0.8636 -0.4572)
			(stroke
				(width 0.1)
				(type default)
			)
			(layer "F.Fab")
		)
		(fp_line
			(start -1.1938 -0.4064)
			(end -0.8636 -0.4064)
			(stroke
				(width 0.1)
				(type default)
			)
			(layer "F.Fab")
		)
		(fp_line
			(start 1.1938 0.4064)
			(end 0.8636 0.4064)
			(stroke
				(width 0.1)
				(type default)
			)
			(layer "F.Fab")
		)
		(fp_line
			(start 0.8636 0.4064)
			(end 0.8636 0.4572)
			(stroke
				(width 0.1)
				(type default)
			)
			(layer "F.Fab")
		)
		(fp_line
			(start -0.8636 0.4064)
			(end -1.1938 0.4064)
			(stroke
				(width 0.1)
				(type default)
			)
			(layer "F.Fab")
		)
		(fp_line
			(start -1.1938 0.4064)
			(end -1.1938 -0.4064)
			(stroke
				(width 0.1)
				(type default)
			)
			(layer "F.Fab")
		)
		(fp_line
			(start 0.8636 0.4572)
			(end -0.8636 0.4572)
			(stroke
				(width 0.1)
				(type default)
			)
			(layer "F.Fab")
		)
		(fp_line
			(start -0.8636 0.4572)
			(end -0.8636 0.4064)
			(stroke
				(width 0.1)
				(type default)
			)
			(layer "F.Fab")
		)
		(pad "1" smd rect
			(at -0.7366 0)
			(size 0.7112 0.8128)
			(layers "F.Cu" "F.Mask" "F.Paste")
			(net "P3V3_M2_0")
		)
		(pad "2" smd rect
			(at 0.7366 0)
			(size 0.7112 0.8128)
			(layers "F.Cu" "F.Mask" "F.Paste")
			(net "GND")
		)
	)
	(footprint ""
		(layer "F.Cu")
		(at 50.317654 -145.008854)
		(property "Reference" "PC1365"
			(at 0 0 0)
			(layer "F.SilkS")
			(hide yes)
			(effects
				(font
					(size 1.27 1.27)
				)
			)
		)
		(property "Value" ""
			(at 0 0 0)
			(layer "F.Fab")
			(effects
				(font
					(size 1.27 1.27)
				)
			)
		)
		(duplicate_pad_numbers_are_jumpers no)
		(fp_line
			(start -0.7874 -0.4064)
			(end 0.7874 -0.4064)
			(stroke
				(width 0.1524)
				(type default)
			)
			(layer "F.SilkS")
		)
		(fp_line
			(start -0.7874 0.4064)
			(end -0.7874 -0.4064)
			(stroke
				(width 0.1524)
				(type default)
			)
			(layer "F.SilkS")
		)
		(fp_line
			(start 0.7874 -0.4064)
			(end 0.7874 0.4064)
			(stroke
				(width 0.1524)
				(type default)
			)
			(layer "F.SilkS")
		)
		(fp_line
			(start 0.7874 0.4064)
			(end -0.7874 0.4064)
			(stroke
				(width 0.1524)
				(type default)
			)
			(layer "F.SilkS")
		)
		(fp_line
			(start -0.67945 -0.305054)
			(end -0.12065 -0.305054)
			(stroke
				(width 0.1)
				(type default)
			)
			(layer "F.Fab")
		)
		(fp_line
			(start -0.67945 0.3048)
			(end -0.67945 -0.305054)
			(stroke
				(width 0.1)
				(type default)
			)
			(layer "F.Fab")
		)
		(fp_line
			(start -0.12065 -0.305054)
			(end -0.12065 -0.2794)
			(stroke
				(width 0.1)
				(type default)
			)
			(layer "F.Fab")
		)
		(fp_line
			(start -0.12065 -0.2794)
			(end 0.12065 -0.2794)
			(stroke
				(width 0.1)
				(type default)
			)
			(layer "F.Fab")
		)
		(fp_line
			(start -0.12065 0.2794)
			(end -0.12065 0.3048)
			(stroke
				(width 0.1)
				(type default)
			)
			(layer "F.Fab")
		)
		(fp_line
			(start -0.12065 0.3048)
			(end -0.67945 0.3048)
			(stroke
				(width 0.1)
				(type default)
			)
			(layer "F.Fab")
		)
		(fp_line
			(start 0.120396 0.2794)
			(end -0.12065 0.2794)
			(stroke
				(width 0.1)
				(type default)
			)
			(layer "F.Fab")
		)
		(fp_line
			(start 0.120396 0.3048)
			(end 0.120396 0.2794)
			(stroke
				(width 0.1)
				(type default)
			)
			(layer "F.Fab")
		)
		(fp_line
			(start 0.12065 -0.3048)
			(end 0.67945 -0.3048)
			(stroke
				(width 0.1)
				(type default)
			)
			(layer "F.Fab")
		)
		(fp_line
			(start 0.12065 -0.2794)
			(end 0.12065 -0.3048)
			(stroke
				(width 0.1)
				(type default)
			)
			(layer "F.Fab")
		)
		(fp_line
			(start 0.67945 -0.3048)
			(end 0.67945 0.3048)
			(stroke
				(width 0.1)
				(type default)
			)
			(layer "F.Fab")
		)
		(fp_line
			(start 0.67945 0.3048)
			(end 0.120396 0.3048)
			(stroke
				(width 0.1)
				(type default)
			)
			(layer "F.Fab")
		)
		(pad "1" smd circle
			(at -0.40005 0)
			(size 0 0)
			(layers "F.Cu" "F.Mask" "F.Paste")
			(net "GND")
		)
		(pad "2" smd circle
			(at 0.40005 0)
			(size 0 0)
			(layers "F.Cu" "F.Mask" "F.Paste")
			(net "PVCCINFAON_CPU1_VREF")
		)
	)
	(footprint ""
		(layer "F.Cu")
		(at 189.65037 -425.287948)
		(property "Reference" "R3923"
			(at 0 0 0)
			(layer "F.SilkS")
			(hide yes)
			(effects
				(font
					(size 1.27 1.27)
				)
			)
		)
		(property "Value" ""
			(at 0 0 0)
			(layer "F.Fab")
			(effects
				(font
					(size 1.27 1.27)
				)
			)
		)
		(duplicate_pad_numbers_are_jumpers no)
		(fp_line
			(start -0.7874 -0.4064)
			(end 0.7874 -0.4064)
			(stroke
				(width 0.1524)
				(type default)
			)
			(layer "F.SilkS")
		)
		(fp_line
			(start -0.7874 0.4064)
			(end -0.7874 -0.4064)
			(stroke
				(width 0.1524)
				(type default)
			)
			(layer "F.SilkS")
		)
		(fp_line
			(start 0.7874 -0.4064)
			(end 0.7874 0.4064)
			(stroke
				(width 0.1524)
				(type default)
			)
			(layer "F.SilkS")
		)
		(fp_line
			(start 0.7874 0.4064)
			(end -0.7874 0.4064)
			(stroke
				(width 0.1524)
				(type default)
			)
			(layer "F.SilkS")
		)
		(fp_line
			(start -0.67945 -0.305054)
			(end -0.12065 -0.305054)
			(stroke
				(width 0.1)
				(type default)
			)
			(layer "F.Fab")
		)
		(fp_line
			(start -0.67945 0.3048)
			(end -0.67945 -0.305054)
			(stroke
				(width 0.1)
				(type default)
			)
			(layer "F.Fab")
		)
		(fp_line
			(start -0.12065 -0.305054)
			(end -0.12065 -0.2794)
			(stroke
				(width 0.1)
				(type default)
			)
			(layer "F.Fab")
		)
		(fp_line
			(start -0.12065 -0.2794)
			(end 0.12065 -0.2794)
			(stroke
				(width 0.1)
				(type default)
			)
			(layer "F.Fab")
		)
		(fp_line
			(start -0.12065 0.2794)
			(end -0.12065 0.3048)
			(stroke
				(width 0.1)
				(type default)
			)
			(layer "F.Fab")
		)
		(fp_line
			(start -0.12065 0.3048)
			(end -0.67945 0.3048)
			(stroke
				(width 0.1)
				(type default)
			)
			(layer "F.Fab")
		)
		(fp_line
			(start 0.120396 0.2794)
			(end -0.12065 0.2794)
			(stroke
				(width 0.1)
				(type default)
			)
			(layer "F.Fab")
		)
		(fp_line
			(start 0.120396 0.3048)
			(end 0.120396 0.2794)
			(stroke
				(width 0.1)
				(type default)
			)
			(layer "F.Fab")
		)
		(fp_line
			(start 0.12065 -0.3048)
			(end 0.67945 -0.3048)
			(stroke
				(width 0.1)
				(type default)
			)
			(layer "F.Fab")
		)
		(fp_line
			(start 0.12065 -0.2794)
			(end 0.12065 -0.3048)
			(stroke
				(width 0.1)
				(type default)
			)
			(layer "F.Fab")
		)
		(fp_line
			(start 0.67945 -0.3048)
			(end 0.67945 0.3048)
			(stroke
				(width 0.1)
				(type default)
			)
			(layer "F.Fab")
		)
		(fp_line
			(start 0.67945 0.3048)
			(end 0.120396 0.3048)
			(stroke
				(width 0.1)
				(type default)
			)
			(layer "F.Fab")
		)
		(pad "1" smd circle
			(at -0.40005 0)
			(size 0 0)
			(layers "F.Cu" "F.Mask" "F.Paste")
			(net "P12V_PSU_FUSE")
		)
		(pad "2" smd circle
			(at 0.40005 0)
			(size 0 0)
			(layers "F.Cu" "F.Mask" "F.Paste")
			(net "PDB_PRSNT_N")
		)
	)
	(footprint ""
		(layer "F.Cu")
		(at 355.8286 -401.955 180)
		(property "Reference" "C2373"
			(at 0 0 180)
			(layer "F.SilkS")
			(hide yes)
			(effects
				(font
					(size 1.27 1.27)
				)
			)
		)
		(property "Value" ""
			(at 0 0 180)
			(layer "F.Fab")
			(effects
				(font
					(size 1.27 1.27)
				)
			)
		)
		(duplicate_pad_numbers_are_jumpers no)
		(fp_line
			(start 0.7874 0.4064)
			(end -0.7874 0.4064)
			(stroke
				(width 0.1524)
				(type default)
			)
			(layer "F.SilkS")
		)
		(fp_line
			(start 0.7874 -0.4064)
			(end 0.7874 0.4064)
			(stroke
				(width 0.1524)
				(type default)
			)
			(layer "F.SilkS")
		)
		(fp_line
			(start -0.7874 0.4064)
			(end -0.7874 -0.4064)
			(stroke
				(width 0.1524)
				(type default)
			)
			(layer "F.SilkS")
		)
		(fp_line
			(start -0.7874 -0.4064)
			(end 0.7874 -0.4064)
			(stroke
				(width 0.1524)
				(type default)
			)
			(layer "F.SilkS")
		)
		(fp_line
			(start 0.67945 0.3048)
			(end 0.120396 0.3048)
			(stroke
				(width 0.1)
				(type default)
			)
			(layer "F.Fab")
		)
		(fp_line
			(start 0.67945 -0.3048)
			(end 0.67945 0.3048)
			(stroke
				(width 0.1)
				(type default)
			)
			(layer "F.Fab")
		)
		(fp_line
			(start 0.12065 -0.2794)
			(end 0.12065 -0.3048)
			(stroke
				(width 0.1)
				(type default)
			)
			(layer "F.Fab")
		)
		(fp_line
			(start 0.12065 -0.3048)
			(end 0.67945 -0.3048)
			(stroke
				(width 0.1)
				(type default)
			)
			(layer "F.Fab")
		)
		(fp_line
			(start 0.120396 0.3048)
			(end 0.120396 0.2794)
			(stroke
				(width 0.1)
				(type default)
			)
			(layer "F.Fab")
		)
		(fp_line
			(start 0.120396 0.2794)
			(end -0.12065 0.2794)
			(stroke
				(width 0.1)
				(type default)
			)
			(layer "F.Fab")
		)
		(fp_line
			(start -0.12065 0.3048)
			(end -0.67945 0.3048)
			(stroke
				(width 0.1)
				(type default)
			)
			(layer "F.Fab")
		)
		(fp_line
			(start -0.12065 0.2794)
			(end -0.12065 0.3048)
			(stroke
				(width 0.1)
				(type default)
			)
			(layer "F.Fab")
		)
		(fp_line
			(start -0.12065 -0.2794)
			(end 0.12065 -0.2794)
			(stroke
				(width 0.1)
				(type default)
			)
			(layer "F.Fab")
		)
		(fp_line
			(start -0.12065 -0.305054)
			(end -0.12065 -0.2794)
			(stroke
				(width 0.1)
				(type default)
			)
			(layer "F.Fab")
		)
		(fp_line
			(start -0.67945 0.3048)
			(end -0.67945 -0.305054)
			(stroke
				(width 0.1)
				(type default)
			)
			(layer "F.Fab")
		)
		(fp_line
			(start -0.67945 -0.305054)
			(end -0.12065 -0.305054)
			(stroke
				(width 0.1)
				(type default)
			)
			(layer "F.Fab")
		)
		(pad "1" smd circle
			(at -0.40005 0 180)
			(size 0 0)
			(layers "F.Cu" "F.Mask" "F.Paste")
			(net "PRSNT_CABLE_SWB_B2_ISO_N")
		)
		(pad "2" smd circle
			(at 0.40005 0 180)
			(size 0 0)
			(layers "F.Cu" "F.Mask" "F.Paste")
			(net "GND")
		)
	)
	(footprint ""
		(layer "F.Cu")
		(at 19.119596 -393.215876 90)
		(property "Reference" "C1865"
			(at 0 0 90)
			(layer "F.SilkS")
			(hide yes)
			(effects
				(font
					(size 1.27 1.27)
				)
			)
		)
		(property "Value" ""
			(at 0 0 90)
			(layer "F.Fab")
			(effects
				(font
					(size 1.27 1.27)
				)
			)
		)
		(duplicate_pad_numbers_are_jumpers no)
		(fp_line
			(start 0.7874 -0.4064)
			(end 0.7874 0.4064)
			(stroke
				(width 0.1524)
				(type default)
			)
			(layer "F.SilkS")
		)
		(fp_line
			(start -0.7874 -0.4064)
			(end 0.7874 -0.4064)
			(stroke
				(width 0.1524)
				(type default)
			)
			(layer "F.SilkS")
		)
		(fp_line
			(start 0.7874 0.4064)
			(end -0.7874 0.4064)
			(stroke
				(width 0.1524)
				(type default)
			)
			(layer "F.SilkS")
		)
		(fp_line
			(start -0.7874 0.4064)
			(end -0.7874 -0.4064)
			(stroke
				(width 0.1524)
				(type default)
			)
			(layer "F.SilkS")
		)
		(fp_line
			(start -0.12065 -0.305054)
			(end -0.12065 -0.2794)
			(stroke
				(width 0.1)
				(type default)
			)
			(layer "F.Fab")
		)
		(fp_line
			(start -0.67945 -0.305054)
			(end -0.12065 -0.305054)
			(stroke
				(width 0.1)
				(type default)
			)
			(layer "F.Fab")
		)
		(fp_line
			(start 0.67945 -0.3048)
			(end 0.67945 0.3048)
			(stroke
				(width 0.1)
				(type default)
			)
			(layer "F.Fab")
		)
		(fp_line
			(start 0.12065 -0.3048)
			(end 0.67945 -0.3048)
			(stroke
				(width 0.1)
				(type default)
			)
			(layer "F.Fab")
		)
		(fp_line
			(start 0.12065 -0.2794)
			(end 0.12065 -0.3048)
			(stroke
				(width 0.1)
				(type default)
			)
			(layer "F.Fab")
		)
		(fp_line
			(start -0.12065 -0.2794)
			(end 0.12065 -0.2794)
			(stroke
				(width 0.1)
				(type default)
			)
			(layer "F.Fab")
		)
		(fp_line
			(start 0.120396 0.2794)
			(end -0.12065 0.2794)
			(stroke
				(width 0.1)
				(type default)
			)
			(layer "F.Fab")
		)
		(fp_line
			(start -0.12065 0.2794)
			(end -0.12065 0.3048)
			(stroke
				(width 0.1)
				(type default)
			)
			(layer "F.Fab")
		)
		(fp_line
			(start 0.67945 0.3048)
			(end 0.120396 0.3048)
			(stroke
				(width 0.1)
				(type default)
			)
			(layer "F.Fab")
		)
		(fp_line
			(start 0.120396 0.3048)
			(end 0.120396 0.2794)
			(stroke
				(width 0.1)
				(type default)
			)
			(layer "F.Fab")
		)
		(fp_line
			(start -0.12065 0.3048)
			(end -0.67945 0.3048)
			(stroke
				(width 0.1)
				(type default)
			)
			(layer "F.Fab")
		)
		(fp_line
			(start -0.67945 0.3048)
			(end -0.67945 -0.305054)
			(stroke
				(width 0.1)
				(type default)
			)
			(layer "F.Fab")
		)
		(pad "1" smd circle
			(at -0.40005 0 90)
			(size 0 0)
			(layers "F.Cu" "F.Mask" "F.Paste")
			(net "P3V3_AUX")
		)
		(pad "2" smd circle
			(at 0.40005 0 90)
			(size 0 0)
			(layers "F.Cu" "F.Mask" "F.Paste")
			(net "GND")
		)
	)
	(footprint ""
		(layer "F.Cu")
		(at 142.0622 -104.116378 -90)
		(property "Reference" "R4038"
			(at 0 0 270)
			(layer "F.SilkS")
			(hide yes)
			(effects
				(font
					(size 1.27 1.27)
				)
			)
		)
		(property "Value" ""
			(at 0 0 270)
			(layer "F.Fab")
			(effects
				(font
					(size 1.27 1.27)
				)
			)
		)
		(duplicate_pad_numbers_are_jumpers no)
		(fp_line
			(start -0.7874 0.4064)
			(end -0.7874 -0.4064)
			(stroke
				(width 0.1524)
				(type default)
			)
			(layer "F.SilkS")
		)
		(fp_line
			(start 0.7874 0.4064)
			(end -0.7874 0.4064)
			(stroke
				(width 0.1524)
				(type default)
			)
			(layer "F.SilkS")
		)
		(fp_line
			(start -0.7874 -0.4064)
			(end 0.7874 -0.4064)
			(stroke
				(width 0.1524)
				(type default)
			)
			(layer "F.SilkS")
		)
		(fp_line
			(start 0.7874 -0.4064)
			(end 0.7874 0.4064)
			(stroke
				(width 0.1524)
				(type default)
			)
			(layer "F.SilkS")
		)
		(fp_line
			(start -0.67945 0.3048)
			(end -0.67945 -0.305054)
			(stroke
				(width 0.1)
				(type default)
			)
			(layer "F.Fab")
		)
		(fp_line
			(start -0.12065 0.3048)
			(end -0.67945 0.3048)
			(stroke
				(width 0.1)
				(type default)
			)
			(layer "F.Fab")
		)
		(fp_line
			(start 0.120396 0.3048)
			(end 0.120396 0.2794)
			(stroke
				(width 0.1)
				(type default)
			)
			(layer "F.Fab")
		)
		(fp_line
			(start 0.67945 0.3048)
			(end 0.120396 0.3048)
			(stroke
				(width 0.1)
				(type default)
			)
			(layer "F.Fab")
		)
		(fp_line
			(start -0.12065 0.2794)
			(end -0.12065 0.3048)
			(stroke
				(width 0.1)
				(type default)
			)
			(layer "F.Fab")
		)
		(fp_line
			(start 0.120396 0.2794)
			(end -0.12065 0.2794)
			(stroke
				(width 0.1)
				(type default)
			)
			(layer "F.Fab")
		)
		(fp_line
			(start -0.12065 -0.2794)
			(end 0.12065 -0.2794)
			(stroke
				(width 0.1)
				(type default)
			)
			(layer "F.Fab")
		)
		(fp_line
			(start 0.12065 -0.2794)
			(end 0.12065 -0.3048)
			(stroke
				(width 0.1)
				(type default)
			)
			(layer "F.Fab")
		)
		(fp_line
			(start 0.12065 -0.3048)
			(end 0.67945 -0.3048)
			(stroke
				(width 0.1)
				(type default)
			)
			(layer "F.Fab")
		)
		(fp_line
			(start 0.67945 -0.3048)
			(end 0.67945 0.3048)
			(stroke
				(width 0.1)
				(type default)
			)
			(layer "F.Fab")
		)
		(fp_line
			(start -0.67945 -0.305054)
			(end -0.12065 -0.305054)
			(stroke
				(width 0.1)
				(type default)
			)
			(layer "F.Fab")
		)
		(fp_line
			(start -0.12065 -0.305054)
			(end -0.12065 -0.2794)
			(stroke
				(width 0.1)
				(type default)
			)
			(layer "F.Fab")
		)
		(pad "1" smd circle
			(at -0.40005 0 270)
			(size 0 0)
			(layers "F.Cu" "F.Mask" "F.Paste")
			(net "P3V3")
		)
		(pad "2" smd circle
			(at 0.40005 0 270)
			(size 0 0)
			(layers "F.Cu" "F.Mask" "F.Paste")
			(net "P0V62_CPU0_ERRS_U306_VREF")
		)
	)
)
